(kicad_pcb
	(version 20260206)
	(generator "pcbnew")
	(generator_version "10.0")
	(general
		(thickness 1.6)
		(legacy_teardrops no)
	)
	(paper "A4")
	(title_block
		(title "baseboard — 13948-1b.1110WZS1818.brd")
		(comment 1 "Honey Badger (Wiwynn) / footprints 50-57 of 2523")
	)
	(layers
		(0 "F.Cu" signal "TOP")
		(4 "In1.Cu" signal "L2GND")
		(6 "In2.Cu" signal "L3")
		(8 "In3.Cu" signal "L4VCC")
		(10 "In4.Cu" signal "L5VCC")
		(12 "In5.Cu" signal "L6")
		(14 "In6.Cu" signal "L7GND")
		(2 "B.Cu" signal "BOTTOM")
		(9 "F.Adhes" user "F.Adhesive")
		(11 "B.Adhes" user "B.Adhesive")
		(13 "F.Paste" user "Package Geometry/Pastemask Top")
		(15 "B.Paste" user "Package Geometry/Pastemask Bottom")
		(5 "F.SilkS" user "Ref Des/Silkscreen Top")
		(7 "B.SilkS" user "Ref Des/Silkscreen Bottom")
		(1 "F.Mask" user "Board Geometry/Soldermask Top")
		(3 "B.Mask" user "Board Geometry/Soldermask Bottom")
		(17 "Dwgs.User" user "User.Drawings")
		(19 "Cmts.User" user "User.Comments")
		(21 "Eco1.User" user "User.Eco1")
		(23 "Eco2.User" user "User.Eco2")
		(25 "Edge.Cuts" user "Board Geometry/Outline")
		(27 "Margin" user)
		(31 "F.CrtYd" user "Package Geometry/Place Bound Top")
		(29 "B.CrtYd" user "Package Geometry/Place Bound Bottom")
		(35 "F.Fab" user "Ref Des/Assembly Top")
		(33 "B.Fab" user "Ref Des/Assembly Bottom")
	)
	(footprint ""
		(layer "F.Cu")
		(at 23.064216 -207.06588 -90)
		(property "Reference" "R571"
			(at 0 0 270)
			(layer "F.SilkS")
			(hide yes)
			(effects
				(font
					(size 1.27 1.27)
				)
			)
		)
		(property "Value" "4K7R2F-GP"
			(at 0.064008 -3.993896 270)
			(unlocked yes)
			(layer "F.Fab")
			(hide yes)
			(effects
				(font
					(size 1.016 1.016)
					(thickness 0.1524)
				)
			)
		)
		(property "Device Type" "R402H16"
			(at 0.064008 -5.517896 270)
			(unlocked yes)
			(layer "F.Fab")
			(hide yes)
			(effects
				(font
					(size 1.016 1.016)
					(thickness 0.1524)
				)
			)
		)
		(duplicate_pad_numbers_are_jumpers no)
		(fp_line
			(start -0.508 -0.9398)
			(end -0.508 0.9398)
			(stroke
				(width 0.1524)
				(type default)
			)
			(layer "F.SilkS")
		)
		(fp_line
			(start 0.508 -0.9398)
			(end -0.508 -0.9398)
			(stroke
				(width 0.1524)
				(type default)
			)
			(layer "F.SilkS")
		)
		(fp_rect
			(start -0.508 0.9398)
			(end 0.508 -0.9398)
			(stroke
				(width 0)
				(type default)
			)
			(fill no)
			(layer "F.CrtYd")
		)
		(fp_rect
			(start -0.508 0.9398)
			(end 0.508 -0.9398)
			(stroke
				(width 0)
				(type default)
			)
			(fill no)
			(layer "F.Fab")
		)
		(pad "1" smd custom
			(at 0 -0.4445 270)
			(size 0.1397 0.1397)
			(layers "F.Cu" "F.Mask" "F.Paste")
			(net "VOL_SEN_ADDR_U17")
			(options
				(clearance outline)
				(anchor circle)
			)
			(primitives
				(gr_poly
					(pts
						(arc
							(start -0.1778 -0.2794)
							(mid -0.249642 -0.249642)
							(end -0.2794 -0.1778)
						)
						(arc
							(start -0.2794 0.1778)
							(mid -0.249642 0.249642)
							(end -0.1778 0.2794)
						)
						(arc
							(start 0.1778 0.2794)
							(mid 0.249642 0.249642)
							(end 0.2794 0.1778)
						)
						(arc
							(start 0.2794 -0.1778)
							(mid 0.249642 -0.249642)
							(end 0.1778 -0.2794)
						)
					)
					(width 0)
					(fill yes)
				)
			)
		)
		(pad "2" smd custom
			(at 0 0.4445 270)
			(size 0.1397 0.1397)
			(layers "F.Cu" "F.Mask" "F.Paste")
			(net "GND")
			(options
				(clearance outline)
				(anchor circle)
			)
			(primitives
				(gr_poly
					(pts
						(arc
							(start -0.1778 -0.2794)
							(mid -0.249642 -0.249642)
							(end -0.2794 -0.1778)
						)
						(arc
							(start -0.2794 0.1778)
							(mid -0.249642 0.249642)
							(end -0.1778 0.2794)
						)
						(arc
							(start 0.1778 0.2794)
							(mid 0.249642 0.249642)
							(end 0.2794 0.1778)
						)
						(arc
							(start 0.2794 -0.1778)
							(mid 0.249642 -0.249642)
							(end 0.1778 -0.2794)
						)
					)
					(width 0)
					(fill yes)
				)
			)
		)
	)
	(footprint ""
		(layer "F.Cu")
		(at 256.794 -126.619)
		(property "Reference" "R7900"
			(at 0 0 0)
			(layer "F.SilkS")
			(hide yes)
			(effects
				(font
					(size 1.27 1.27)
				)
			)
		)
		(property "Value" "0R2J-2-GP"
			(at 0.064008 -3.993896 0)
			(unlocked yes)
			(layer "F.Fab")
			(hide yes)
			(effects
				(font
					(size 1.016 1.016)
					(thickness 0.1524)
				)
			)
		)
		(property "Device Type" "R402H16"
			(at 0.064008 -5.517896 0)
			(unlocked yes)
			(layer "F.Fab")
			(hide yes)
			(effects
				(font
					(size 1.016 1.016)
					(thickness 0.1524)
				)
			)
		)
		(duplicate_pad_numbers_are_jumpers no)
		(fp_line
			(start -0.508 -0.9398)
			(end -0.508 0.9398)
			(stroke
				(width 0.1524)
				(type default)
			)
			(layer "F.SilkS")
		)
		(fp_line
			(start 0.508 -0.9398)
			(end -0.508 -0.9398)
			(stroke
				(width 0.1524)
				(type default)
			)
			(layer "F.SilkS")
		)
		(fp_rect
			(start -0.508 0.9398)
			(end 0.508 -0.9398)
			(stroke
				(width 0)
				(type default)
			)
			(fill no)
			(layer "F.CrtYd")
		)
		(fp_rect
			(start -0.508 0.9398)
			(end 0.508 -0.9398)
			(stroke
				(width 0)
				(type default)
			)
			(fill no)
			(layer "F.Fab")
		)
		(pad "1" smd custom
			(at 0 -0.4445)
			(size 0.1397 0.1397)
			(layers "F.Cu" "F.Mask" "F.Paste")
			(net "CPU_U192_PIN2_TX")
			(options
				(clearance outline)
				(anchor circle)
			)
			(primitives
				(gr_poly
					(pts
						(arc
							(start -0.1778 -0.2794)
							(mid -0.249642 -0.249642)
							(end -0.2794 -0.1778)
						)
						(arc
							(start -0.2794 0.1778)
							(mid -0.249642 0.249642)
							(end -0.1778 0.2794)
						)
						(arc
							(start 0.1778 0.2794)
							(mid 0.249642 0.249642)
							(end 0.2794 0.1778)
						)
						(arc
							(start 0.2794 -0.1778)
							(mid 0.249642 -0.249642)
							(end 0.1778 -0.2794)
						)
					)
					(width 0)
					(fill yes)
				)
			)
		)
		(pad "2" smd custom
			(at 0 0.4445)
			(size 0.1397 0.1397)
			(layers "F.Cu" "F.Mask" "F.Paste")
			(net "CPU_TXD")
			(options
				(clearance outline)
				(anchor circle)
			)
			(primitives
				(gr_poly
					(pts
						(arc
							(start -0.1778 -0.2794)
							(mid -0.249642 -0.249642)
							(end -0.2794 -0.1778)
						)
						(arc
							(start -0.2794 0.1778)
							(mid -0.249642 0.249642)
							(end -0.1778 0.2794)
						)
						(arc
							(start 0.1778 0.2794)
							(mid 0.249642 0.249642)
							(end 0.2794 0.1778)
						)
						(arc
							(start 0.2794 -0.1778)
							(mid 0.249642 -0.249642)
							(end 0.1778 -0.2794)
						)
					)
					(width 0)
					(fill yes)
				)
			)
		)
	)
	(footprint ""
		(layer "F.Cu")
		(at 208.407 -97.028 -90)
		(property "Reference" "PC144"
			(at 0 0 270)
			(layer "F.SilkS")
			(hide yes)
			(effects
				(font
					(size 1.27 1.27)
				)
			)
		)
		(property "Value" "SC10U6D3V5KX-1GP"
			(at -0.0762 -6.1214 270)
			(unlocked yes)
			(layer "F.Fab")
			(hide yes)
			(effects
				(font
					(size 1.016 1.016)
					(thickness 0.1524)
				)
			)
		)
		(property "Device Type" "C805H54"
			(at -0.0762 -8.1534 270)
			(unlocked yes)
			(layer "F.Fab")
			(hide yes)
			(effects
				(font
					(size 1.016 1.016)
					(thickness 0.1524)
				)
			)
		)
		(duplicate_pad_numbers_are_jumpers no)
		(fp_line
			(start 0.635 0)
			(end -0.635 0)
			(stroke
				(width 0.508)
				(type default)
			)
			(layer "F.SilkS")
		)
		(fp_rect
			(start -0.9652 1.778)
			(end 0.9652 -1.778)
			(stroke
				(width 0)
				(type default)
			)
			(fill no)
			(layer "F.CrtYd")
		)
		(fp_poly
			(pts
				(xy -0.9652 -1.778) (xy 0.9652 -1.778) (xy 0.9652 1.778) (xy -0.9652 1.778)
			)
			(stroke
				(width 0)
				(type default)
			)
			(fill no)
			(layer "F.Fab")
		)
		(pad "1" smd rect
			(at 0 -0.9652 270)
			(size 1.397 1.143)
			(layers "F.Cu" "F.Mask" "F.Paste")
			(net "P1V5_C")
		)
		(pad "2" smd rect
			(at 0 0.9652 270)
			(size 1.397 1.143)
			(layers "F.Cu" "F.Mask" "F.Paste")
			(net "GND")
		)
	)
	(footprint ""
		(layer "F.Cu")
		(at 104.15397 -114.3 180)
		(property "Reference" "SC1088"
			(at 0 0 180)
			(layer "F.SilkS")
			(hide yes)
			(effects
				(font
					(size 1.27 1.27)
				)
			)
		)
		(property "Value" "SCD01U10V1KX-GP"
			(at -2.8321 -1.7399 180)
			(unlocked yes)
			(layer "F.Fab")
			(hide yes)
			(effects
				(font
					(size 1.016 1.016)
					(thickness 0.1524)
				)
			)
		)
		(property "Device Type" "C0201H13"
			(at -2.8321 -3.2639 180)
			(unlocked yes)
			(layer "F.Fab")
			(hide yes)
			(effects
				(font
					(size 1.016 1.016)
					(thickness 0.1524)
				)
			)
		)
		(duplicate_pad_numbers_are_jumpers no)
		(fp_rect
			(start -0.2794 0.6477)
			(end 0.2794 -0.6477)
			(stroke
				(width 0)
				(type default)
			)
			(fill no)
			(layer "F.CrtYd")
		)
		(fp_rect
			(start -0.2794 0.6477)
			(end 0.2794 -0.6477)
			(stroke
				(width 0)
				(type default)
			)
			(fill no)
			(layer "F.Fab")
		)
		(pad "1" smd custom
			(at 0 -0.2794 180)
			(size 0.0762 0.0762)
			(layers "F.Cu" "F.Mask" "F.Paste")
			(net "SAS_HDD_TX10_P")
			(options
				(clearance outline)
				(anchor circle)
			)
			(primitives
				(gr_poly
					(pts
						(arc
							(start 0.1524 -0.127)
							(mid 0.137521 -0.162921)
							(end 0.1016 -0.1778)
						)
						(arc
							(start -0.1016 -0.1778)
							(mid -0.137521 -0.162921)
							(end -0.1524 -0.127)
						)
						(arc
							(start -0.1524 0.127)
							(mid -0.137521 0.162921)
							(end -0.1016 0.1778)
						)
						(arc
							(start 0.1016 0.1778)
							(mid 0.137521 0.162921)
							(end 0.1524 0.127)
						)
					)
					(width 0)
					(fill yes)
				)
			)
		)
		(pad "2" smd custom
			(at 0 0.2794 180)
			(size 0.0762 0.0762)
			(layers "F.Cu" "F.Mask" "F.Paste")
			(net "SAS_EXP_GF_TX_DP14")
			(options
				(clearance outline)
				(anchor circle)
			)
			(primitives
				(gr_poly
					(pts
						(arc
							(start 0.1524 -0.127)
							(mid 0.137521 -0.162921)
							(end 0.1016 -0.1778)
						)
						(arc
							(start -0.1016 -0.1778)
							(mid -0.137521 -0.162921)
							(end -0.1524 -0.127)
						)
						(arc
							(start -0.1524 0.127)
							(mid -0.137521 0.162921)
							(end -0.1016 0.1778)
						)
						(arc
							(start 0.1016 0.1778)
							(mid 0.137521 0.162921)
							(end 0.1524 0.127)
						)
					)
					(width 0)
					(fill yes)
				)
			)
		)
	)
	(footprint ""
		(layer "F.Cu")
		(at 274.193 -179.705 90)
		(property "Reference" "R363"
			(at 0 0 90)
			(layer "F.SilkS")
			(hide yes)
			(effects
				(font
					(size 1.27 1.27)
				)
			)
		)
		(property "Value" "3K3R2F-2-GP"
			(at 0.064008 -3.993896 90)
			(unlocked yes)
			(layer "F.Fab")
			(hide yes)
			(effects
				(font
					(size 1.016 1.016)
					(thickness 0.1524)
				)
			)
		)
		(property "Device Type" "R402H16"
			(at 0.064008 -5.517896 90)
			(unlocked yes)
			(layer "F.Fab")
			(hide yes)
			(effects
				(font
					(size 1.016 1.016)
					(thickness 0.1524)
				)
			)
		)
		(duplicate_pad_numbers_are_jumpers no)
		(fp_line
			(start 0.508 -0.9398)
			(end -0.508 -0.9398)
			(stroke
				(width 0.1524)
				(type default)
			)
			(layer "F.SilkS")
		)
		(fp_line
			(start -0.508 -0.9398)
			(end -0.508 0.9398)
			(stroke
				(width 0.1524)
				(type default)
			)
			(layer "F.SilkS")
		)
		(fp_rect
			(start -0.508 0.9398)
			(end 0.508 -0.9398)
			(stroke
				(width 0)
				(type default)
			)
			(fill no)
			(layer "F.CrtYd")
		)
		(fp_rect
			(start -0.508 0.9398)
			(end 0.508 -0.9398)
			(stroke
				(width 0)
				(type default)
			)
			(fill no)
			(layer "F.Fab")
		)
		(pad "1" smd custom
			(at 0 -0.4445 90)
			(size 0.1397 0.1397)
			(layers "F.Cu" "F.Mask" "F.Paste")
			(net "P3V3_STBY")
			(options
				(clearance outline)
				(anchor circle)
			)
			(primitives
				(gr_poly
					(pts
						(arc
							(start -0.1778 -0.2794)
							(mid -0.249642 -0.249642)
							(end -0.2794 -0.1778)
						)
						(arc
							(start -0.2794 0.1778)
							(mid -0.249642 0.249642)
							(end -0.1778 0.2794)
						)
						(arc
							(start 0.1778 0.2794)
							(mid 0.249642 0.249642)
							(end 0.2794 0.1778)
						)
						(arc
							(start 0.2794 -0.1778)
							(mid 0.249642 -0.249642)
							(end 0.1778 -0.2794)
						)
					)
					(width 0)
					(fill yes)
				)
			)
		)
		(pad "2" smd custom
			(at 0 0.4445 90)
			(size 0.1397 0.1397)
			(layers "F.Cu" "F.Mask" "F.Paste")
			(net "ROMA6")
			(options
				(clearance outline)
				(anchor circle)
			)
			(primitives
				(gr_poly
					(pts
						(arc
							(start -0.1778 -0.2794)
							(mid -0.249642 -0.249642)
							(end -0.2794 -0.1778)
						)
						(arc
							(start -0.2794 0.1778)
							(mid -0.249642 0.249642)
							(end -0.1778 0.2794)
						)
						(arc
							(start 0.1778 0.2794)
							(mid 0.249642 0.249642)
							(end 0.2794 0.1778)
						)
						(arc
							(start 0.2794 -0.1778)
							(mid 0.249642 -0.249642)
							(end 0.1778 -0.2794)
						)
					)
					(width 0)
					(fill yes)
				)
			)
		)
	)
	(footprint ""
		(layer "F.Cu")
		(at 278.511 -182.118)
		(property "Reference" "TP96"
			(at 0 0 0)
			(layer "F.SilkS")
			(hide yes)
			(effects
				(font
					(size 1.27 1.27)
				)
			)
		)
		(property "Value" "TPAD28"
			(at 0.0127 -1.8034 0)
			(unlocked yes)
			(layer "F.Fab")
			(hide yes)
			(effects
				(font
					(size 1.016 1.016)
					(thickness 0.1524)
				)
			)
		)
		(property "Device Type" "TPAD28"
			(at 0.0127 -3.3274 0)
			(unlocked yes)
			(layer "F.Fab")
			(hide yes)
			(effects
				(font
					(size 1.016 1.016)
					(thickness 0.1524)
				)
			)
		)
		(duplicate_pad_numbers_are_jumpers no)
		(fp_poly
			(pts
				(arc
					(start 0.3556 0)
					(mid -0.3556 0)
					(end 0.3556 0)
				)
			)
			(stroke
				(width 0)
				(type default)
			)
			(fill no)
			(layer "F.CrtYd")
		)
		(fp_poly
			(pts
				(arc
					(start 0.6096 0)
					(mid -0.6096 0)
					(end 0.6096 0)
				)
			)
			(stroke
				(width 0)
				(type default)
			)
			(fill no)
			(layer "F.Fab")
		)
		(pad "1" smd circle
			(at 0 0)
			(size 0.7112 0.7112)
			(layers "F.Cu" "F.Mask" "F.Paste")
			(net "TP_BMC_GPIOR4")
		)
	)
	(footprint ""
		(layer "F.Cu")
		(at 78.8924 -6.985 90)
		(property "Reference" "PC205"
			(at 0 0 90)
			(layer "F.SilkS")
			(hide yes)
			(effects
				(font
					(size 1.27 1.27)
				)
			)
		)
		(property "Value" "SC10U25V6KX-1GP"
			(at -0.0762 -5.1308 90)
			(unlocked yes)
			(layer "F.Fab")
			(hide yes)
			(effects
				(font
					(size 1.016 1.016)
					(thickness 0.1524)
				)
			)
		)
		(property "Device Type" "C1206H71"
			(at -0.127 -6.6548 90)
			(unlocked yes)
			(layer "F.Fab")
			(hide yes)
			(effects
				(font
					(size 1.016 1.016)
					(thickness 0.1524)
				)
			)
		)
		(duplicate_pad_numbers_are_jumpers no)
		(fp_line
			(start 1.016 -2.2352)
			(end 1.016 -0.8382)
			(stroke
				(width 0.1524)
				(type default)
			)
			(layer "F.SilkS")
		)
		(fp_line
			(start -1.016 -2.2352)
			(end 1.016 -2.2352)
			(stroke
				(width 0.1524)
				(type default)
			)
			(layer "F.SilkS")
		)
		(fp_line
			(start -1.016 -0.8382)
			(end -1.016 -2.2352)
			(stroke
				(width 0.1524)
				(type default)
			)
			(layer "F.SilkS")
		)
		(fp_line
			(start 1.016 0.8382)
			(end 1.016 2.2352)
			(stroke
				(width 0.1524)
				(type default)
			)
			(layer "F.SilkS")
		)
		(fp_line
			(start 1.016 2.2352)
			(end -1.016 2.2352)
			(stroke
				(width 0.1524)
				(type default)
			)
			(layer "F.SilkS")
		)
		(fp_line
			(start -1.016 2.2352)
			(end -1.016 0.8382)
			(stroke
				(width 0.1524)
				(type default)
			)
			(layer "F.SilkS")
		)
		(fp_rect
			(start -1.0922 2.3114)
			(end 1.0922 -2.3114)
			(stroke
				(width 0)
				(type default)
			)
			(fill no)
			(layer "F.CrtYd")
		)
		(fp_poly
			(pts
				(xy 1.0922 -2.3114) (xy 1.0922 2.3114) (xy -1.0922 2.3114) (xy -1.0922 -2.3114)
			)
			(stroke
				(width 0)
				(type default)
			)
			(fill no)
			(layer "F.Fab")
		)
		(pad "1" smd rect
			(at 0 -1.397 90)
			(size 1.651 1.27)
			(layers "F.Cu" "F.Mask" "F.Paste")
			(net "VT235_VDDH")
		)
		(pad "2" smd rect
			(at 0 1.397 90)
			(size 1.651 1.27)
			(layers "F.Cu" "F.Mask" "F.Paste")
			(net "GND")
		)
	)
	(footprint ""
		(layer "F.Cu")
		(at 223.393 -112.395 180)
		(property "Reference" "R603"
			(at 0 0 180)
			(layer "F.SilkS")
			(hide yes)
			(effects
				(font
					(size 1.27 1.27)
				)
			)
		)
		(property "Value" "4K7R2F-GP"
			(at 0.064008 -3.993896 180)
			(unlocked yes)
			(layer "F.Fab")
			(hide yes)
			(effects
				(font
					(size 1.016 1.016)
					(thickness 0.1524)
				)
			)
		)
		(property "Device Type" "R402H16"
			(at 0.064008 -5.517896 180)
			(unlocked yes)
			(layer "F.Fab")
			(hide yes)
			(effects
				(font
					(size 1.016 1.016)
					(thickness 0.1524)
				)
			)
		)
		(duplicate_pad_numbers_are_jumpers no)
		(fp_line
			(start 0.508 -0.9398)
			(end -0.508 -0.9398)
			(stroke
				(width 0.1524)
				(type default)
			)
			(layer "F.SilkS")
		)
		(fp_line
			(start -0.508 -0.9398)
			(end -0.508 0.9398)
			(stroke
				(width 0.1524)
				(type default)
			)
			(layer "F.SilkS")
		)
		(fp_rect
			(start -0.508 0.9398)
			(end 0.508 -0.9398)
			(stroke
				(width 0)
				(type default)
			)
			(fill no)
			(layer "F.CrtYd")
		)
		(fp_rect
			(start -0.508 0.9398)
			(end 0.508 -0.9398)
			(stroke
				(width 0)
				(type default)
			)
			(fill no)
			(layer "F.Fab")
		)
		(pad "1" smd custom
			(at 0 -0.4445 180)
			(size 0.1397 0.1397)
			(layers "F.Cu" "F.Mask" "F.Paste")
			(net "P1V8_STBY")
			(options
				(clearance outline)
				(anchor circle)
			)
			(primitives
				(gr_poly
					(pts
						(arc
							(start -0.1778 -0.2794)
							(mid -0.249642 -0.249642)
							(end -0.2794 -0.1778)
						)
						(arc
							(start -0.2794 0.1778)
							(mid -0.249642 0.249642)
							(end -0.1778 0.2794)
						)
						(arc
							(start 0.1778 0.2794)
							(mid 0.249642 0.249642)
							(end 0.2794 0.1778)
						)
						(arc
							(start 0.2794 -0.1778)
							(mid 0.249642 -0.249642)
							(end 0.1778 -0.2794)
						)
					)
					(width 0)
					(fill yes)
				)
			)
		)
		(pad "2" smd custom
			(at 0 0.4445 180)
			(size 0.1397 0.1397)
			(layers "F.Cu" "F.Mask" "F.Paste")
			(net "P1V8_PG_R_2")
			(options
				(clearance outline)
				(anchor circle)
			)
			(primitives
				(gr_poly
					(pts
						(arc
							(start -0.1778 -0.2794)
							(mid -0.249642 -0.249642)
							(end -0.2794 -0.1778)
						)
						(arc
							(start -0.2794 0.1778)
							(mid -0.249642 0.249642)
							(end -0.1778 0.2794)
						)
						(arc
							(start 0.1778 0.2794)
							(mid 0.249642 0.249642)
							(end 0.2794 0.1778)
						)
						(arc
							(start 0.2794 -0.1778)
							(mid 0.249642 -0.249642)
							(end 0.1778 -0.2794)
						)
					)
					(width 0)
					(fill yes)
				)
			)
		)
	)
)
